(kicad_pcb
	(version 20260206)
	(generator "pcbnew")
	(generator_version "10.0")
	(general
		(thickness 1.6)
		(legacy_teardrops no)
	)
	(paper "A4")
	(title_block
		(title "03242023_DA0F0TMBIJ0_F0T_Motherboard_J_brd_V01_OCP.brd")
		(comment 1 "Grand Teton / footprints 1652-1658 of 6105")
	)
	(layers
		(0 "F.Cu" signal "TOP")
		(4 "In1.Cu" signal "GND")
		(6 "In2.Cu" signal "IN1")
		(8 "In3.Cu" signal "GND1")
		(10 "In4.Cu" signal "IN2")
		(12 "In5.Cu" signal "GND2")
		(14 "In6.Cu" signal "IN3")
		(16 "In7.Cu" signal "GND3")
		(18 "In8.Cu" signal "VCC")
		(20 "In9.Cu" signal "VCC1")
		(22 "In10.Cu" signal "GND4")
		(24 "In11.Cu" signal "IN4")
		(26 "In12.Cu" signal "GND5")
		(28 "In13.Cu" signal "IN5")
		(30 "In14.Cu" signal "GND6")
		(32 "In15.Cu" signal "IN6")
		(34 "In16.Cu" signal "GND7")
		(2 "B.Cu" signal "BOTTOM")
		(9 "F.Adhes" user "F.Adhesive")
		(11 "B.Adhes" user "B.Adhesive")
		(13 "F.Paste" user "Package Geometry/Pastemask Top")
		(15 "B.Paste" user "Package Geometry/Pastemask Bottom")
		(5 "F.SilkS" user "Ref Des/Silkscreen Top")
		(7 "B.SilkS" user "Ref Des/Silkscreen Bottom")
		(1 "F.Mask" user "Board Geometry/Soldermask Top")
		(3 "B.Mask" user "Board Geometry/Soldermask Bottom")
		(17 "Dwgs.User" user "User.Drawings")
		(19 "Cmts.User" user "User.Comments")
		(21 "Eco1.User" user "User.Eco1")
		(23 "Eco2.User" user "User.Eco2")
		(25 "Edge.Cuts" user "Board Geometry/Outline")
		(27 "Margin" user)
		(31 "F.CrtYd" user "Package Geometry/Place Bound Top")
		(29 "B.CrtYd" user "Package Geometry/Place Bound Bottom")
		(35 "F.Fab" user "Ref Des/Assembly Top")
		(33 "B.Fab" user "Ref Des/Assembly Bottom")
	)
	(footprint ""
		(layer "F.Cu")
		(at 193.90868 -359.349548 180)
		(property "Reference" "R627"
			(at 0 0 180)
			(layer "F.SilkS")
			(hide yes)
			(effects
				(font
					(size 1.27 1.27)
				)
			)
		)
		(property "Value" ""
			(at 0 0 180)
			(layer "F.Fab")
			(effects
				(font
					(size 1.27 1.27)
				)
			)
		)
		(duplicate_pad_numbers_are_jumpers no)
		(fp_line
			(start 0.7874 0.4064)
			(end -0.7874 0.4064)
			(stroke
				(width 0.1524)
				(type default)
			)
			(layer "F.SilkS")
		)
		(fp_line
			(start 0.7874 -0.4064)
			(end 0.7874 0.4064)
			(stroke
				(width 0.1524)
				(type default)
			)
			(layer "F.SilkS")
		)
		(fp_line
			(start -0.7874 0.4064)
			(end -0.7874 -0.4064)
			(stroke
				(width 0.1524)
				(type default)
			)
			(layer "F.SilkS")
		)
		(fp_line
			(start -0.7874 -0.4064)
			(end 0.7874 -0.4064)
			(stroke
				(width 0.1524)
				(type default)
			)
			(layer "F.SilkS")
		)
		(fp_line
			(start 0.67945 0.3048)
			(end 0.120396 0.3048)
			(stroke
				(width 0.1)
				(type default)
			)
			(layer "F.Fab")
		)
		(fp_line
			(start 0.67945 -0.3048)
			(end 0.67945 0.3048)
			(stroke
				(width 0.1)
				(type default)
			)
			(layer "F.Fab")
		)
		(fp_line
			(start 0.12065 -0.2794)
			(end 0.12065 -0.3048)
			(stroke
				(width 0.1)
				(type default)
			)
			(layer "F.Fab")
		)
		(fp_line
			(start 0.12065 -0.3048)
			(end 0.67945 -0.3048)
			(stroke
				(width 0.1)
				(type default)
			)
			(layer "F.Fab")
		)
		(fp_line
			(start 0.120396 0.3048)
			(end 0.120396 0.2794)
			(stroke
				(width 0.1)
				(type default)
			)
			(layer "F.Fab")
		)
		(fp_line
			(start 0.120396 0.2794)
			(end -0.12065 0.2794)
			(stroke
				(width 0.1)
				(type default)
			)
			(layer "F.Fab")
		)
		(fp_line
			(start -0.12065 0.3048)
			(end -0.67945 0.3048)
			(stroke
				(width 0.1)
				(type default)
			)
			(layer "F.Fab")
		)
		(fp_line
			(start -0.12065 0.2794)
			(end -0.12065 0.3048)
			(stroke
				(width 0.1)
				(type default)
			)
			(layer "F.Fab")
		)
		(fp_line
			(start -0.12065 -0.2794)
			(end 0.12065 -0.2794)
			(stroke
				(width 0.1)
				(type default)
			)
			(layer "F.Fab")
		)
		(fp_line
			(start -0.12065 -0.305054)
			(end -0.12065 -0.2794)
			(stroke
				(width 0.1)
				(type default)
			)
			(layer "F.Fab")
		)
		(fp_line
			(start -0.67945 0.3048)
			(end -0.67945 -0.305054)
			(stroke
				(width 0.1)
				(type default)
			)
			(layer "F.Fab")
		)
		(fp_line
			(start -0.67945 -0.305054)
			(end -0.12065 -0.305054)
			(stroke
				(width 0.1)
				(type default)
			)
			(layer "F.Fab")
		)
		(pad "1" smd circle
			(at -0.40005 0 180)
			(size 0 0)
			(layers "F.Cu" "F.Mask" "F.Paste")
			(net "P3V3_AUX")
		)
		(pad "2" smd circle
			(at 0.40005 0 180)
			(size 0 0)
			(layers "F.Cu" "F.Mask" "F.Paste")
			(net "PD_PIROM_CPU1_ADDR1")
		)
	)
	(footprint ""
		(layer "F.Cu")
		(at 209.070956 -30.276292 90)
		(property "Reference" "R3624"
			(at 0 0 90)
			(layer "F.SilkS")
			(hide yes)
			(effects
				(font
					(size 1.27 1.27)
				)
			)
		)
		(property "Value" ""
			(at 0 0 90)
			(layer "F.Fab")
			(effects
				(font
					(size 1.27 1.27)
				)
			)
		)
		(duplicate_pad_numbers_are_jumpers no)
		(fp_line
			(start 0.7874 -0.4064)
			(end 0.7874 0.4064)
			(stroke
				(width 0.1524)
				(type default)
			)
			(layer "F.SilkS")
		)
		(fp_line
			(start -0.7874 -0.4064)
			(end 0.7874 -0.4064)
			(stroke
				(width 0.1524)
				(type default)
			)
			(layer "F.SilkS")
		)
		(fp_line
			(start 0.7874 0.4064)
			(end -0.7874 0.4064)
			(stroke
				(width 0.1524)
				(type default)
			)
			(layer "F.SilkS")
		)
		(fp_line
			(start -0.7874 0.4064)
			(end -0.7874 -0.4064)
			(stroke
				(width 0.1524)
				(type default)
			)
			(layer "F.SilkS")
		)
		(fp_line
			(start -0.12065 -0.305054)
			(end -0.12065 -0.2794)
			(stroke
				(width 0.1)
				(type default)
			)
			(layer "F.Fab")
		)
		(fp_line
			(start -0.67945 -0.305054)
			(end -0.12065 -0.305054)
			(stroke
				(width 0.1)
				(type default)
			)
			(layer "F.Fab")
		)
		(fp_line
			(start 0.67945 -0.3048)
			(end 0.67945 0.3048)
			(stroke
				(width 0.1)
				(type default)
			)
			(layer "F.Fab")
		)
		(fp_line
			(start 0.12065 -0.3048)
			(end 0.67945 -0.3048)
			(stroke
				(width 0.1)
				(type default)
			)
			(layer "F.Fab")
		)
		(fp_line
			(start 0.12065 -0.2794)
			(end 0.12065 -0.3048)
			(stroke
				(width 0.1)
				(type default)
			)
			(layer "F.Fab")
		)
		(fp_line
			(start -0.12065 -0.2794)
			(end 0.12065 -0.2794)
			(stroke
				(width 0.1)
				(type default)
			)
			(layer "F.Fab")
		)
		(fp_line
			(start 0.120396 0.2794)
			(end -0.12065 0.2794)
			(stroke
				(width 0.1)
				(type default)
			)
			(layer "F.Fab")
		)
		(fp_line
			(start -0.12065 0.2794)
			(end -0.12065 0.3048)
			(stroke
				(width 0.1)
				(type default)
			)
			(layer "F.Fab")
		)
		(fp_line
			(start 0.67945 0.3048)
			(end 0.120396 0.3048)
			(stroke
				(width 0.1)
				(type default)
			)
			(layer "F.Fab")
		)
		(fp_line
			(start 0.120396 0.3048)
			(end 0.120396 0.2794)
			(stroke
				(width 0.1)
				(type default)
			)
			(layer "F.Fab")
		)
		(fp_line
			(start -0.12065 0.3048)
			(end -0.67945 0.3048)
			(stroke
				(width 0.1)
				(type default)
			)
			(layer "F.Fab")
		)
		(fp_line
			(start -0.67945 0.3048)
			(end -0.67945 -0.305054)
			(stroke
				(width 0.1)
				(type default)
			)
			(layer "F.Fab")
		)
		(pad "1" smd circle
			(at -0.40005 0 90)
			(size 0 0)
			(layers "F.Cu" "F.Mask" "F.Paste")
			(net "P3V3_AUX")
		)
		(pad "2" smd circle
			(at 0.40005 0 90)
			(size 0 0)
			(layers "F.Cu" "F.Mask" "F.Paste")
			(net "INA230_5_A1")
		)
	)
	(footprint ""
		(layer "F.Cu")
		(at 354.282248 -247.715024 90)
		(property "Reference" "C975"
			(at 0 0 90)
			(layer "F.SilkS")
			(hide yes)
			(effects
				(font
					(size 1.27 1.27)
				)
			)
		)
		(property "Value" ""
			(at 0 0 90)
			(layer "F.Fab")
			(effects
				(font
					(size 1.27 1.27)
				)
			)
		)
		(duplicate_pad_numbers_are_jumpers no)
		(fp_line
			(start 0.7874 -0.4064)
			(end 0.7874 0.4064)
			(stroke
				(width 0.1524)
				(type default)
			)
			(layer "F.SilkS")
		)
		(fp_line
			(start -0.7874 -0.4064)
			(end 0.7874 -0.4064)
			(stroke
				(width 0.1524)
				(type default)
			)
			(layer "F.SilkS")
		)
		(fp_line
			(start 0.7874 0.4064)
			(end -0.7874 0.4064)
			(stroke
				(width 0.1524)
				(type default)
			)
			(layer "F.SilkS")
		)
		(fp_line
			(start -0.7874 0.4064)
			(end -0.7874 -0.4064)
			(stroke
				(width 0.1524)
				(type default)
			)
			(layer "F.SilkS")
		)
		(fp_line
			(start -0.12065 -0.305054)
			(end -0.12065 -0.2794)
			(stroke
				(width 0.1)
				(type default)
			)
			(layer "F.Fab")
		)
		(fp_line
			(start -0.67945 -0.305054)
			(end -0.12065 -0.305054)
			(stroke
				(width 0.1)
				(type default)
			)
			(layer "F.Fab")
		)
		(fp_line
			(start 0.67945 -0.3048)
			(end 0.67945 0.3048)
			(stroke
				(width 0.1)
				(type default)
			)
			(layer "F.Fab")
		)
		(fp_line
			(start 0.12065 -0.3048)
			(end 0.67945 -0.3048)
			(stroke
				(width 0.1)
				(type default)
			)
			(layer "F.Fab")
		)
		(fp_line
			(start 0.12065 -0.2794)
			(end 0.12065 -0.3048)
			(stroke
				(width 0.1)
				(type default)
			)
			(layer "F.Fab")
		)
		(fp_line
			(start -0.12065 -0.2794)
			(end 0.12065 -0.2794)
			(stroke
				(width 0.1)
				(type default)
			)
			(layer "F.Fab")
		)
		(fp_line
			(start 0.120396 0.2794)
			(end -0.12065 0.2794)
			(stroke
				(width 0.1)
				(type default)
			)
			(layer "F.Fab")
		)
		(fp_line
			(start -0.12065 0.2794)
			(end -0.12065 0.3048)
			(stroke
				(width 0.1)
				(type default)
			)
			(layer "F.Fab")
		)
		(fp_line
			(start 0.67945 0.3048)
			(end 0.120396 0.3048)
			(stroke
				(width 0.1)
				(type default)
			)
			(layer "F.Fab")
		)
		(fp_line
			(start 0.120396 0.3048)
			(end 0.120396 0.2794)
			(stroke
				(width 0.1)
				(type default)
			)
			(layer "F.Fab")
		)
		(fp_line
			(start -0.12065 0.3048)
			(end -0.67945 0.3048)
			(stroke
				(width 0.1)
				(type default)
			)
			(layer "F.Fab")
		)
		(fp_line
			(start -0.67945 0.3048)
			(end -0.67945 -0.305054)
			(stroke
				(width 0.1)
				(type default)
			)
			(layer "F.Fab")
		)
		(pad "1" smd circle
			(at -0.40005 0 90)
			(size 0 0)
			(layers "F.Cu" "F.Mask" "F.Paste")
			(net "PVCCIN_CPU0")
		)
		(pad "2" smd circle
			(at 0.40005 0 90)
			(size 0 0)
			(layers "F.Cu" "F.Mask" "F.Paste")
			(net "GND")
		)
	)
	(footprint ""
		(layer "F.Cu")
		(at 197.41388 -107.495848)
		(property "Reference" "R109"
			(at 0 0 0)
			(layer "F.SilkS")
			(hide yes)
			(effects
				(font
					(size 1.27 1.27)
				)
			)
		)
		(property "Value" ""
			(at 0 0 0)
			(layer "F.Fab")
			(effects
				(font
					(size 1.27 1.27)
				)
			)
		)
		(duplicate_pad_numbers_are_jumpers no)
		(fp_line
			(start -0.7874 -0.4064)
			(end 0.7874 -0.4064)
			(stroke
				(width 0.1524)
				(type default)
			)
			(layer "F.SilkS")
		)
		(fp_line
			(start -0.7874 0.4064)
			(end -0.7874 -0.4064)
			(stroke
				(width 0.1524)
				(type default)
			)
			(layer "F.SilkS")
		)
		(fp_line
			(start 0.7874 -0.4064)
			(end 0.7874 0.4064)
			(stroke
				(width 0.1524)
				(type default)
			)
			(layer "F.SilkS")
		)
		(fp_line
			(start 0.7874 0.4064)
			(end -0.7874 0.4064)
			(stroke
				(width 0.1524)
				(type default)
			)
			(layer "F.SilkS")
		)
		(fp_line
			(start -0.67945 -0.305054)
			(end -0.12065 -0.305054)
			(stroke
				(width 0.1)
				(type default)
			)
			(layer "F.Fab")
		)
		(fp_line
			(start -0.67945 0.3048)
			(end -0.67945 -0.305054)
			(stroke
				(width 0.1)
				(type default)
			)
			(layer "F.Fab")
		)
		(fp_line
			(start -0.12065 -0.305054)
			(end -0.12065 -0.2794)
			(stroke
				(width 0.1)
				(type default)
			)
			(layer "F.Fab")
		)
		(fp_line
			(start -0.12065 -0.2794)
			(end 0.12065 -0.2794)
			(stroke
				(width 0.1)
				(type default)
			)
			(layer "F.Fab")
		)
		(fp_line
			(start -0.12065 0.2794)
			(end -0.12065 0.3048)
			(stroke
				(width 0.1)
				(type default)
			)
			(layer "F.Fab")
		)
		(fp_line
			(start -0.12065 0.3048)
			(end -0.67945 0.3048)
			(stroke
				(width 0.1)
				(type default)
			)
			(layer "F.Fab")
		)
		(fp_line
			(start 0.120396 0.2794)
			(end -0.12065 0.2794)
			(stroke
				(width 0.1)
				(type default)
			)
			(layer "F.Fab")
		)
		(fp_line
			(start 0.120396 0.3048)
			(end 0.120396 0.2794)
			(stroke
				(width 0.1)
				(type default)
			)
			(layer "F.Fab")
		)
		(fp_line
			(start 0.12065 -0.3048)
			(end 0.67945 -0.3048)
			(stroke
				(width 0.1)
				(type default)
			)
			(layer "F.Fab")
		)
		(fp_line
			(start 0.12065 -0.2794)
			(end 0.12065 -0.3048)
			(stroke
				(width 0.1)
				(type default)
			)
			(layer "F.Fab")
		)
		(fp_line
			(start 0.67945 -0.3048)
			(end 0.67945 0.3048)
			(stroke
				(width 0.1)
				(type default)
			)
			(layer "F.Fab")
		)
		(fp_line
			(start 0.67945 0.3048)
			(end 0.120396 0.3048)
			(stroke
				(width 0.1)
				(type default)
			)
			(layer "F.Fab")
		)
		(pad "1" smd circle
			(at -0.40005 0)
			(size 0 0)
			(layers "F.Cu" "F.Mask" "F.Paste")
			(net "FM_PLD_CLK_25M_R_EN")
		)
		(pad "2" smd circle
			(at 0.40005 0)
			(size 0 0)
			(layers "F.Cu" "F.Mask" "F.Paste")
			(net "FM_PLD_CLK_25M_EN")
		)
	)
	(footprint ""
		(layer "F.Cu")
		(at 442.91123 -370.248434)
		(property "Reference" "C1331"
			(at 0 0 0)
			(layer "F.SilkS")
			(hide yes)
			(effects
				(font
					(size 1.27 1.27)
				)
			)
		)
		(property "Value" ""
			(at 0 0 0)
			(layer "F.Fab")
			(effects
				(font
					(size 1.27 1.27)
				)
			)
		)
		(duplicate_pad_numbers_are_jumpers no)
		(fp_line
			(start -1.524 -0.762)
			(end 1.524 -0.762)
			(stroke
				(width 0.1524)
				(type default)
			)
			(layer "F.SilkS")
		)
		(fp_line
			(start -1.524 0.762)
			(end -1.524 -0.762)
			(stroke
				(width 0.1524)
				(type default)
			)
			(layer "F.SilkS")
		)
		(fp_line
			(start 1.524 -0.762)
			(end 1.524 0.762)
			(stroke
				(width 0.1524)
				(type default)
			)
			(layer "F.SilkS")
		)
		(fp_line
			(start 1.524 0.762)
			(end -1.524 0.762)
			(stroke
				(width 0.1524)
				(type default)
			)
			(layer "F.SilkS")
		)
		(fp_line
			(start -1.1049 -0.724916)
			(end -1.1049 0.724916)
			(stroke
				(width 0.1)
				(type default)
			)
			(layer "F.Fab")
		)
		(fp_line
			(start -1.1049 0.724916)
			(end 1.1049 0.724916)
			(stroke
				(width 0.1)
				(type default)
			)
			(layer "F.Fab")
		)
		(fp_line
			(start 1.1049 -0.724916)
			(end -1.1049 -0.724916)
			(stroke
				(width 0.1)
				(type default)
			)
			(layer "F.Fab")
		)
		(fp_line
			(start 1.1049 0.724916)
			(end 1.1049 -0.724916)
			(stroke
				(width 0.1)
				(type default)
			)
			(layer "F.Fab")
		)
		(pad "1" smd rect
			(at -0.889 0 180)
			(size 1.016 1.27)
			(layers "F.Cu" "F.Mask" "F.Paste")
			(net "P5V")
		)
		(pad "2" smd rect
			(at 0.889 0 180)
			(size 1.016 1.27)
			(layers "F.Cu" "F.Mask" "F.Paste")
			(net "GND")
		)
	)
	(footprint ""
		(layer "F.Cu")
		(at 218.011502 -72.015858 180)
		(property "Reference" "PR3971"
			(at 0 0 180)
			(layer "F.SilkS")
			(hide yes)
			(effects
				(font
					(size 1.27 1.27)
				)
			)
		)
		(property "Value" ""
			(at 0 0 180)
			(layer "F.Fab")
			(effects
				(font
					(size 1.27 1.27)
				)
			)
		)
		(duplicate_pad_numbers_are_jumpers no)
		(fp_line
			(start 0.7874 0.4064)
			(end -0.7874 0.4064)
			(stroke
				(width 0.1524)
				(type default)
			)
			(layer "F.SilkS")
		)
		(fp_line
			(start 0.7874 -0.4064)
			(end 0.7874 0.4064)
			(stroke
				(width 0.1524)
				(type default)
			)
			(layer "F.SilkS")
		)
		(fp_line
			(start -0.7874 0.4064)
			(end -0.7874 -0.4064)
			(stroke
				(width 0.1524)
				(type default)
			)
			(layer "F.SilkS")
		)
		(fp_line
			(start -0.7874 -0.4064)
			(end 0.7874 -0.4064)
			(stroke
				(width 0.1524)
				(type default)
			)
			(layer "F.SilkS")
		)
		(fp_line
			(start 0.67945 0.3048)
			(end 0.120396 0.3048)
			(stroke
				(width 0.1)
				(type default)
			)
			(layer "F.Fab")
		)
		(fp_line
			(start 0.67945 -0.3048)
			(end 0.67945 0.3048)
			(stroke
				(width 0.1)
				(type default)
			)
			(layer "F.Fab")
		)
		(fp_line
			(start 0.12065 -0.2794)
			(end 0.12065 -0.3048)
			(stroke
				(width 0.1)
				(type default)
			)
			(layer "F.Fab")
		)
		(fp_line
			(start 0.12065 -0.3048)
			(end 0.67945 -0.3048)
			(stroke
				(width 0.1)
				(type default)
			)
			(layer "F.Fab")
		)
		(fp_line
			(start 0.120396 0.3048)
			(end 0.120396 0.2794)
			(stroke
				(width 0.1)
				(type default)
			)
			(layer "F.Fab")
		)
		(fp_line
			(start 0.120396 0.2794)
			(end -0.12065 0.2794)
			(stroke
				(width 0.1)
				(type default)
			)
			(layer "F.Fab")
		)
		(fp_line
			(start -0.12065 0.3048)
			(end -0.67945 0.3048)
			(stroke
				(width 0.1)
				(type default)
			)
			(layer "F.Fab")
		)
		(fp_line
			(start -0.12065 0.2794)
			(end -0.12065 0.3048)
			(stroke
				(width 0.1)
				(type default)
			)
			(layer "F.Fab")
		)
		(fp_line
			(start -0.12065 -0.2794)
			(end 0.12065 -0.2794)
			(stroke
				(width 0.1)
				(type default)
			)
			(layer "F.Fab")
		)
		(fp_line
			(start -0.12065 -0.305054)
			(end -0.12065 -0.2794)
			(stroke
				(width 0.1)
				(type default)
			)
			(layer "F.Fab")
		)
		(fp_line
			(start -0.67945 0.3048)
			(end -0.67945 -0.305054)
			(stroke
				(width 0.1)
				(type default)
			)
			(layer "F.Fab")
		)
		(fp_line
			(start -0.67945 -0.305054)
			(end -0.12065 -0.305054)
			(stroke
				(width 0.1)
				(type default)
			)
			(layer "F.Fab")
		)
		(pad "1" smd circle
			(at -0.40005 0 180)
			(size 0 0)
			(layers "F.Cu" "F.Mask" "F.Paste")
			(net "P3V3_E1S_SENSE_0")
		)
		(pad "2" smd circle
			(at 0.40005 0 180)
			(size 0 0)
			(layers "F.Cu" "F.Mask" "F.Paste")
			(net "GND")
		)
	)
	(footprint ""
		(layer "F.Cu")
		(at 326.743568 -408.517344 -90)
		(property "Reference" "C916"
			(at 0 0 270)
			(layer "F.SilkS")
			(hide yes)
			(effects
				(font
					(size 1.27 1.27)
				)
			)
		)
		(property "Value" ""
			(at 0 0 270)
			(layer "F.Fab")
			(effects
				(font
					(size 1.27 1.27)
				)
			)
		)
		(duplicate_pad_numbers_are_jumpers no)
		(fp_line
			(start -0.299974 0.150114)
			(end -0.299974 -0.150114)
			(stroke
				(width 0.1)
				(type default)
			)
			(layer "F.Fab")
		)
		(fp_line
			(start 0.299974 0.150114)
			(end -0.299974 0.150114)
			(stroke
				(width 0.1)
				(type default)
			)
			(layer "F.Fab")
		)
		(fp_line
			(start -0.299974 -0.150114)
			(end 0.299974 -0.150114)
			(stroke
				(width 0.1)
				(type default)
			)
			(layer "F.Fab")
		)
		(fp_line
			(start 0.299974 -0.150114)
			(end 0.299974 0.150114)
			(stroke
				(width 0.1)
				(type default)
			)
			(layer "F.Fab")
		)
		(pad "1" smd rect
			(at -0.2667 0 270)
			(size 0.3048 0.381)
			(layers "F.Cu" "F.Mask" "F.Paste")
			(net "P5E_CPU0_PE0_TX_C_DN<8>")
		)
		(pad "2" smd rect
			(at 0.2667 0 270)
			(size 0.3048 0.381)
			(layers "F.Cu" "F.Mask" "F.Paste")
			(net "P5E_CPU0_PE0_TX_DN<8>")
		)
	)
)
